# T6G (Grand Teton) — schematic netlist excerpt (pin names and nets, part order shuffled) for the footprints in the layout excerpt that follows; sources: Cadence DE-HDL packaged netlist, KiCad conversion of 04192023_DAF0TMB3IC0_F0TG_MB_C_brd_V02_OCP.brd

PC218_2  Q_CAP  22UF 16V 20% X6S  pkg C0805  page 208 : A = SW_P12V_AUX_PVDD11_S3_P0_FLT ; B = GND
R438  Q_RES  4.7K 5% EMPTY  pkg 0402LF  page 28 : A = CPU0_FORCE_SELFREFRESH ; B = PVDD18_S5_P0
R1154  Q_RES  0 5% CHIP  pkg 0402LF  page 160 : A = SMB_CPU0_CPU1_SEC_SDA_R1 ; B = SMB_CPU0_CPU1_SEC_SDA_R2

(kicad_pcb
	(version 20260206)
	(generator "pcbnew")
	(generator_version "10.0")
	(general
		(thickness 1.6)
		(legacy_teardrops no)
	)
	(paper "A4")
	(title_block
		(title "04192023_DAF0TMB3IC0_F0TG_MB_C_brd_V02_OCP.brd")
		(comment 1 "Grand Teton / footprints 7398-7400 of 8354")
	)
	(layers
		(0 "F.Cu" signal "TOP")
		(4 "In1.Cu" signal "GND")
		(6 "In2.Cu" signal "IN1")
		(8 "In3.Cu" signal "GND1")
		(10 "In4.Cu" signal "IN2")
		(12 "In5.Cu" signal "GND2")
		(14 "In6.Cu" signal "IN3")
		(16 "In7.Cu" signal "GND3")
		(18 "In8.Cu" signal "VCC")
		(20 "In9.Cu" signal "VCC1")
		(22 "In10.Cu" signal "GND4")
		(24 "In11.Cu" signal "IN4")
		(26 "In12.Cu" signal "GND5")
		(28 "In13.Cu" signal "IN5")
		(30 "In14.Cu" signal "GND6")
		(32 "In15.Cu" signal "IN6")
		(34 "In16.Cu" signal "GND7")
		(2 "B.Cu" signal "BOTTOM")
		(9 "F.Adhes" user "F.Adhesive")
		(11 "B.Adhes" user "B.Adhesive")
		(13 "F.Paste" user "Package Geometry/Pastemask Top")
		(15 "B.Paste" user "Package Geometry/Pastemask Bottom")
		(5 "F.SilkS" user "Ref Des/Silkscreen Top")
		(7 "B.SilkS" user "Ref Des/Silkscreen Bottom")
		(1 "F.Mask" user "Board Geometry/Soldermask Top")
		(3 "B.Mask" user "Board Geometry/Soldermask Bottom")
		(17 "Dwgs.User" user "User.Drawings")
		(19 "Cmts.User" user "User.Comments")
		(21 "Eco1.User" user "User.Eco1")
		(23 "Eco2.User" user "User.Eco2")
		(25 "Edge.Cuts" user "Board Geometry/Outline")
		(27 "Margin" user)
		(31 "F.CrtYd" user "Package Geometry/Place Bound Top")
		(29 "B.CrtYd" user "Package Geometry/Place Bound Bottom")
		(35 "F.Fab" user "Ref Des/Assembly Top")
		(33 "B.Fab" user "Ref Des/Assembly Bottom")
	)
	(footprint ""
		(layer "B.Cu")
		(at 244.221 -228.092 -90)
		(property "Reference" "R1154"
			(at 0 0 90)
			(layer "B.SilkS")
			(hide yes)
			(effects
				(font
					(size 1.27 1.27)
				)
				(justify mirror)
			)
		)
		(property "Value" ""
			(at 0 0 90)
			(layer "B.Fab")
			(effects
				(font
					(size 1.27 1.27)
				)
				(justify mirror)
			)
		)
		(duplicate_pad_numbers_are_jumpers no)
		(fp_line
			(start -0.7874 0.4064)
			(end 0.7874 0.4064)
			(stroke
				(width 0.1524)
				(type default)
			)
			(layer "B.SilkS")
		)
		(fp_line
			(start 0.7874 0.4064)
			(end 0.7874 -0.4064)
			(stroke
				(width 0.1524)
				(type default)
			)
			(layer "B.SilkS")
		)
		(fp_line
			(start -0.7874 -0.4064)
			(end -0.7874 0.4064)
			(stroke
				(width 0.1524)
				(type default)
			)
			(layer "B.SilkS")
		)
		(fp_line
			(start 0.7874 -0.4064)
			(end -0.7874 -0.4064)
			(stroke
				(width 0.1524)
				(type default)
			)
			(layer "B.SilkS")
		)
		(fp_line
			(start -0.67945 0.3048)
			(end -0.120396 0.3048)
			(stroke
				(width 0.1)
				(type default)
			)
			(layer "B.Fab")
		)
		(fp_line
			(start -0.120396 0.3048)
			(end -0.120396 0.2794)
			(stroke
				(width 0.1)
				(type default)
			)
			(layer "B.Fab")
		)
		(fp_line
			(start 0.12065 0.3048)
			(end 0.67945 0.3048)
			(stroke
				(width 0.1)
				(type default)
			)
			(layer "B.Fab")
		)
		(fp_line
			(start 0.67945 0.3048)
			(end 0.67945 -0.305054)
			(stroke
				(width 0.1)
				(type default)
			)
			(layer "B.Fab")
		)
		(fp_line
			(start -0.120396 0.2794)
			(end 0.12065 0.2794)
			(stroke
				(width 0.1)
				(type default)
			)
			(layer "B.Fab")
		)
		(fp_line
			(start 0.12065 0.2794)
			(end 0.12065 0.3048)
			(stroke
				(width 0.1)
				(type default)
			)
			(layer "B.Fab")
		)
		(fp_line
			(start -0.12065 -0.2794)
			(end -0.12065 -0.3048)
			(stroke
				(width 0.1)
				(type default)
			)
			(layer "B.Fab")
		)
		(fp_line
			(start 0.12065 -0.2794)
			(end -0.12065 -0.2794)
			(stroke
				(width 0.1)
				(type default)
			)
			(layer "B.Fab")
		)
		(fp_line
			(start -0.67945 -0.3048)
			(end -0.67945 0.3048)
			(stroke
				(width 0.1)
				(type default)
			)
			(layer "B.Fab")
		)
		(fp_line
			(start -0.12065 -0.3048)
			(end -0.67945 -0.3048)
			(stroke
				(width 0.1)
				(type default)
			)
			(layer "B.Fab")
		)
		(fp_line
			(start 0.12065 -0.305054)
			(end 0.12065 -0.2794)
			(stroke
				(width 0.1)
				(type default)
			)
			(layer "B.Fab")
		)
		(fp_line
			(start 0.67945 -0.305054)
			(end 0.12065 -0.305054)
			(stroke
				(width 0.1)
				(type default)
			)
			(layer "B.Fab")
		)
		(pad "1" smd circle
			(at 0.40005 0 90)
			(size 0 0)
			(layers "B.Cu" "B.Mask" "B.Paste")
			(net "SMB_CPU0_CPU1_SEC_SDA_R1")
		)
		(pad "2" smd circle
			(at -0.40005 0 90)
			(size 0 0)
			(layers "B.Cu" "B.Mask" "B.Paste")
			(net "SMB_CPU0_CPU1_SEC_SDA_R2")
		)
	)
	(footprint ""
		(layer "B.Cu")
		(at 323.386958 -198.964296)
		(property "Reference" "R438"
			(at 0 0 0)
			(layer "B.SilkS")
			(hide yes)
			(effects
				(font
					(size 1.27 1.27)
				)
				(justify mirror)
			)
		)
		(property "Value" ""
			(at 0 0 0)
			(layer "B.Fab")
			(effects
				(font
					(size 1.27 1.27)
				)
				(justify mirror)
			)
		)
		(duplicate_pad_numbers_are_jumpers no)
		(fp_line
			(start -0.7874 -0.4064)
			(end -0.7874 0.4064)
			(stroke
				(width 0.1524)
				(type default)
			)
			(layer "B.SilkS")
		)
		(fp_line
			(start -0.7874 0.4064)
			(end 0.7874 0.4064)
			(stroke
				(width 0.1524)
				(type default)
			)
			(layer "B.SilkS")
		)
		(fp_line
			(start 0.7874 -0.4064)
			(end -0.7874 -0.4064)
			(stroke
				(width 0.1524)
				(type default)
			)
			(layer "B.SilkS")
		)
		(fp_line
			(start 0.7874 0.4064)
			(end 0.7874 -0.4064)
			(stroke
				(width 0.1524)
				(type default)
			)
			(layer "B.SilkS")
		)
		(fp_line
			(start -0.67945 -0.3048)
			(end -0.67945 0.3048)
			(stroke
				(width 0.1)
				(type default)
			)
			(layer "B.Fab")
		)
		(fp_line
			(start -0.67945 0.3048)
			(end -0.120396 0.3048)
			(stroke
				(width 0.1)
				(type default)
			)
			(layer "B.Fab")
		)
		(fp_line
			(start -0.12065 -0.3048)
			(end -0.67945 -0.3048)
			(stroke
				(width 0.1)
				(type default)
			)
			(layer "B.Fab")
		)
		(fp_line
			(start -0.12065 -0.2794)
			(end -0.12065 -0.3048)
			(stroke
				(width 0.1)
				(type default)
			)
			(layer "B.Fab")
		)
		(fp_line
			(start -0.120396 0.2794)
			(end 0.12065 0.2794)
			(stroke
				(width 0.1)
				(type default)
			)
			(layer "B.Fab")
		)
		(fp_line
			(start -0.120396 0.3048)
			(end -0.120396 0.2794)
			(stroke
				(width 0.1)
				(type default)
			)
			(layer "B.Fab")
		)
		(fp_line
			(start 0.12065 -0.305054)
			(end 0.12065 -0.2794)
			(stroke
				(width 0.1)
				(type default)
			)
			(layer "B.Fab")
		)
		(fp_line
			(start 0.12065 -0.2794)
			(end -0.12065 -0.2794)
			(stroke
				(width 0.1)
				(type default)
			)
			(layer "B.Fab")
		)
		(fp_line
			(start 0.12065 0.2794)
			(end 0.12065 0.3048)
			(stroke
				(width 0.1)
				(type default)
			)
			(layer "B.Fab")
		)
		(fp_line
			(start 0.12065 0.3048)
			(end 0.67945 0.3048)
			(stroke
				(width 0.1)
				(type default)
			)
			(layer "B.Fab")
		)
		(fp_line
			(start 0.67945 -0.305054)
			(end 0.12065 -0.305054)
			(stroke
				(width 0.1)
				(type default)
			)
			(layer "B.Fab")
		)
		(fp_line
			(start 0.67945 0.3048)
			(end 0.67945 -0.305054)
			(stroke
				(width 0.1)
				(type default)
			)
			(layer "B.Fab")
		)
		(pad "1" smd circle
			(at 0.40005 0 180)
			(size 0 0)
			(layers "B.Cu" "B.Mask" "B.Paste")
			(net "CPU0_FORCE_SELFREFRESH")
		)
		(pad "2" smd circle
			(at -0.40005 0 180)
			(size 0 0)
			(layers "B.Cu" "B.Mask" "B.Paste")
			(net "PVDD18_S5_P0")
		)
	)
	(footprint ""
		(layer "B.Cu")
		(at 436.839614 -351.095818 90)
		(property "Reference" "PC218_2"
			(at 0 0 90)
			(layer "B.SilkS")
			(hide yes)
			(effects
				(font
					(size 1.27 1.27)
				)
				(justify mirror)
			)
		)
		(property "Value" ""
			(at 0 0 90)
			(layer "B.Fab")
			(effects
				(font
					(size 1.27 1.27)
				)
				(justify mirror)
			)
		)
		(duplicate_pad_numbers_are_jumpers no)
		(fp_line
			(start 1.524 -0.762)
			(end -1.524 -0.762)
			(stroke
				(width 0.1524)
				(type default)
			)
			(layer "B.SilkS")
		)
		(fp_line
			(start -1.524 -0.762)
			(end -1.524 0.762)
			(stroke
				(width 0.1524)
				(type default)
			)
			(layer "B.SilkS")
		)
		(fp_line
			(start 1.524 0.762)
			(end 1.524 -0.762)
			(stroke
				(width 0.1524)
				(type default)
			)
			(layer "B.SilkS")
		)
		(fp_line
			(start -1.524 0.762)
			(end 1.524 0.762)
			(stroke
				(width 0.1524)
				(type default)
			)
			(layer "B.SilkS")
		)
		(fp_line
			(start 1.1049 -0.724916)
			(end 1.1049 0.724916)
			(stroke
				(width 0.1)
				(type default)
			)
			(layer "B.Fab")
		)
		(fp_line
			(start -1.1049 -0.724916)
			(end 1.1049 -0.724916)
			(stroke
				(width 0.1)
				(type default)
			)
			(layer "B.Fab")
		)
		(fp_line
			(start 1.1049 0.724916)
			(end -1.1049 0.724916)
			(stroke
				(width 0.1)
				(type default)
			)
			(layer "B.Fab")
		)
		(fp_line
			(start -1.1049 0.724916)
			(end -1.1049 -0.724916)
			(stroke
				(width 0.1)
				(type default)
			)
			(layer "B.Fab")
		)
		(pad "1" smd rect
			(at 0.889 0 90)
			(size 1.016 1.27)
			(layers "B.Cu" "B.Mask" "B.Paste")
			(net "SW_P12V_AUX_PVDD11_S3_P0_FLT")
		)
		(pad "2" smd rect
			(at -0.889 0 90)
			(size 1.016 1.27)
			(layers "B.Cu" "B.Mask" "B.Paste")
			(net "GND")
		)
	)
)
